(kicad_pcb
	(version 20241229)
	(generator "pcbnew")
	(generator_version "9.0")
	(general
		(thickness 1.61)
		(legacy_teardrops no)
	)
	(paper "A3")
	(title_block
		(title "SO-DIMM DDR5 Tester")
		(date "2025-11-26")
		(rev "1.3.0")
		(comment 9 "footprints 535-540 of 627")
	)
	(layers
		(0 "F.Cu" signal)
		(4 "In1.Cu" power)
		(6 "In2.Cu" mixed)
		(8 "In3.Cu" power)
		(10 "In4.Cu" mixed)
		(12 "In5.Cu" power)
		(14 "In6.Cu" mixed)
		(16 "In7.Cu" power)
		(18 "In8.Cu" power)
		(20 "In9.Cu" mixed)
		(22 "In10.Cu" power)
		(2 "B.Cu" signal)
		(9 "F.Adhes" user "F.Adhesive")
		(11 "B.Adhes" user "B.Adhesive")
		(13 "F.Paste" user)
		(15 "B.Paste" user)
		(5 "F.SilkS" user "F.Silkscreen")
		(7 "B.SilkS" user "B.Silkscreen")
		(1 "F.Mask" user)
		(3 "B.Mask" user)
		(17 "Dwgs.User" user "User.Drawings")
		(19 "Cmts.User" user "User.Comments")
		(21 "Eco1.User" user "User.Eco1")
		(23 "Eco2.User" user "User.Eco2")
		(25 "Edge.Cuts" user)
		(27 "Margin" user)
		(31 "F.CrtYd" user "F.Courtyard")
		(29 "B.CrtYd" user "B.Courtyard")
		(35 "F.Fab" user)
		(33 "B.Fab" user)
	)
	(footprint "antmicro-footprints:C_0402_1005Metric"
		(layer "B.Cu")
		(at 142.375501 186.801 -90)
		(descr "Capacitor SMD 0402 (1005 Metric), square (rectangular) end terminal, IPC_7351 nominal, (Body size source: IPC-SM-782 page 76, https://www.pcb-3d.com/wordpress/wp-content/uploads/ipc-sm-782a_amendment_1_and_2.pdf)")
		(tags "capacitor 0402")
		(property "Reference" "C56"
			(at 0 1.17 90)
			(layer "B.SilkS")
			(hide yes)
			(effects
				(font
					(size 0.7 0.7)
					(thickness 0.15)
				)
				(justify left bottom mirror)
			)
		)
		(property "Value" "C_100n_0402"
			(at 0 -1.169 90)
			(layer "B.Fab")
			(effects
				(font
					(size 0.7 0.7)
					(thickness 0.15)
				)
				(justify left bottom mirror)
			)
		)
		(property "Datasheet" "https://www.murata.com/products/productdetail?partno=GRM155R61H104KE14%23"
			(at 0 0 270)
			(layer "F.Fab")
			(hide yes)
			(effects
				(font
					(size 1.27 1.27)
					(thickness 0.15)
				)
			)
		)
		(property "Author" "Antmicro"
			(at -44.425499 329.176501 0)
			(layer "B.Fab")
			(hide yes)
			(effects
				(font
					(size 1 1)
					(thickness 0.15)
				)
				(justify mirror)
			)
		)
		(property "Dielectric" "X5R"
			(at -44.425499 329.176501 0)
			(layer "B.Fab")
			(hide yes)
			(effects
				(font
					(size 1 1)
					(thickness 0.15)
				)
				(justify mirror)
			)
		)
		(property "License" "Apache-2.0"
			(at -44.425499 329.176501 0)
			(layer "B.Fab")
			(hide yes)
			(effects
				(font
					(size 1 1)
					(thickness 0.15)
				)
				(justify mirror)
			)
		)
		(property "MPN" "GRM155R61H104KE14D"
			(at -44.425499 329.176501 0)
			(layer "B.Fab")
			(hide yes)
			(effects
				(font
					(size 1 1)
					(thickness 0.15)
				)
				(justify mirror)
			)
		)
		(property "Manufacturer" "Murata"
			(at -44.425499 329.176501 0)
			(layer "B.Fab")
			(hide yes)
			(effects
				(font
					(size 1 1)
					(thickness 0.15)
				)
				(justify mirror)
			)
		)
		(property "Val" "100n"
			(at -44.425499 329.176501 0)
			(layer "B.Fab")
			(hide yes)
			(effects
				(font
					(size 1 1)
					(thickness 0.15)
				)
				(justify mirror)
			)
		)
		(property "Voltage" "50V"
			(at -44.425499 329.176501 0)
			(layer "B.Fab")
			(hide yes)
			(effects
				(font
					(size 1 1)
					(thickness 0.15)
				)
				(justify mirror)
			)
		)
		(sheetname "/FPGA power/")
		(sheetfile "fpga-power.kicad_sch")
		(attr smd)
		(fp_rect
			(start -0.9656 0.4572)
			(end 0.9652 -0.4828)
			(stroke
				(width 0.05)
				(type solid)
			)
			(fill no)
			(layer "B.CrtYd")
		)
		(fp_line
			(start -0.5 0.25)
			(end 0.498 0.25)
			(stroke
				(width 0.15)
				(type solid)
			)
			(layer "B.Fab")
		)
		(fp_line
			(start 0.498 0.25)
			(end 0.498 -0.248)
			(stroke
				(width 0.15)
				(type solid)
			)
			(layer "B.Fab")
		)
		(fp_line
			(start -0.5 -0.248)
			(end -0.5 0.25)
			(stroke
				(width 0.15)
				(type solid)
			)
			(layer "B.Fab")
		)
		(fp_line
			(start 0.498 -0.248)
			(end -0.5 -0.248)
			(stroke
				(width 0.15)
				(type solid)
			)
			(layer "B.Fab")
		)
		(pad "1" smd roundrect
			(at -0.5 0 180)
			(size 0.6 0.6)
			(layers "B.Cu" "B.Mask" "B.Paste")
			(roundrect_rratio 0.25)
			(net 1 "GND")
			(pintype "passive")
		)
		(pad "2" smd roundrect
			(at 0.498 0 270)
			(size 0.6 0.6)
			(layers "B.Cu" "B.Mask" "B.Paste")
			(roundrect_rratio 0.25)
			(net 200 "+3V3")
			(pintype "passive")
		)
	)
	(footprint "antmicro-footprints:C_0402_1005Metric"
		(layer "B.Cu")
		(at 151.875001 177.3005 180)
		(descr "Capacitor SMD 0402 (1005 Metric), square (rectangular) end terminal, IPC_7351 nominal, (Body size source: IPC-SM-782 page 76, https://www.pcb-3d.com/wordpress/wp-content/uploads/ipc-sm-782a_amendment_1_and_2.pdf)")
		(tags "capacitor 0402")
		(property "Reference" "C105"
			(at 0 1.17 0)
			(layer "B.SilkS")
			(hide yes)
			(effects
				(font
					(size 0.7 0.7)
					(thickness 0.15)
				)
				(justify left bottom mirror)
			)
		)
		(property "Value" "C_100n_0402"
			(at 0 -1.169 0)
			(layer "B.Fab")
			(effects
				(font
					(size 0.7 0.7)
					(thickness 0.15)
				)
				(justify left bottom mirror)
			)
		)
		(property "Datasheet" "https://www.murata.com/products/productdetail?partno=GRM155R61H104KE14%23"
			(at 0 0 180)
			(layer "F.Fab")
			(hide yes)
			(effects
				(font
					(size 1.27 1.27)
					(thickness 0.15)
				)
			)
		)
		(property "Author" "Antmicro"
			(at 303.750002 354.601 0)
			(layer "B.Fab")
			(hide yes)
			(effects
				(font
					(size 1 1)
					(thickness 0.15)
				)
				(justify mirror)
			)
		)
		(property "Dielectric" "X5R"
			(at 303.750002 354.601 0)
			(layer "B.Fab")
			(hide yes)
			(effects
				(font
					(size 1 1)
					(thickness 0.15)
				)
				(justify mirror)
			)
		)
		(property "License" "Apache-2.0"
			(at 303.750002 354.601 0)
			(layer "B.Fab")
			(hide yes)
			(effects
				(font
					(size 1 1)
					(thickness 0.15)
				)
				(justify mirror)
			)
		)
		(property "MPN" "GRM155R61H104KE14D"
			(at 303.750002 354.601 0)
			(layer "B.Fab")
			(hide yes)
			(effects
				(font
					(size 1 1)
					(thickness 0.15)
				)
				(justify mirror)
			)
		)
		(property "Manufacturer" "Murata"
			(at 303.750002 354.601 0)
			(layer "B.Fab")
			(hide yes)
			(effects
				(font
					(size 1 1)
					(thickness 0.15)
				)
				(justify mirror)
			)
		)
		(property "Val" "100n"
			(at 303.750002 354.601 0)
			(layer "B.Fab")
			(hide yes)
			(effects
				(font
					(size 1 1)
					(thickness 0.15)
				)
				(justify mirror)
			)
		)
		(property "Voltage" "50V"
			(at 303.750002 354.601 0)
			(layer "B.Fab")
			(hide yes)
			(effects
				(font
					(size 1 1)
					(thickness 0.15)
				)
				(justify mirror)
			)
		)
		(sheetname "/FPGA power/")
		(sheetfile "fpga-power.kicad_sch")
		(attr smd)
		(fp_rect
			(start -0.9656 0.4572)
			(end 0.9652 -0.4828)
			(stroke
				(width 0.05)
				(type solid)
			)
			(fill no)
			(layer "B.CrtYd")
		)
		(fp_line
			(start 0.498 0.25)
			(end 0.498 -0.248)
			(stroke
				(width 0.15)
				(type solid)
			)
			(layer "B.Fab")
		)
		(fp_line
			(start 0.498 -0.248)
			(end -0.5 -0.248)
			(stroke
				(width 0.15)
				(type solid)
			)
			(layer "B.Fab")
		)
		(fp_line
			(start -0.5 0.25)
			(end 0.498 0.25)
			(stroke
				(width 0.15)
				(type solid)
			)
			(layer "B.Fab")
		)
		(fp_line
			(start -0.5 -0.248)
			(end -0.5 0.25)
			(stroke
				(width 0.15)
				(type solid)
			)
			(layer "B.Fab")
		)
		(pad "1" smd roundrect
			(at -0.5 0 90)
			(size 0.6 0.6)
			(layers "B.Cu" "B.Mask" "B.Paste")
			(roundrect_rratio 0.25)
			(net 1 "GND")
			(pintype "passive")
		)
		(pad "2" smd roundrect
			(at 0.498 0 180)
			(size 0.6 0.6)
			(layers "B.Cu" "B.Mask" "B.Paste")
			(roundrect_rratio 0.25)
			(net 226 "+1V2_MGTAVTT")
			(pintype "passive")
		)
	)
	(footprint "antmicro-footprints:C_0603_1608Metric"
		(layer "B.Cu")
		(at 138.877001 169.4025 -90)
		(descr "Capacitor SMD 0603")
		(tags "capacitor 0603")
		(property "Reference" "C14"
			(at 0 0.9 90)
			(layer "B.SilkS")
			(hide yes)
			(effects
				(font
					(size 0.7 0.7)
					(thickness 0.15)
				)
				(justify left bottom mirror)
			)
		)
		(property "Value" "C_47u_0603"
			(at 0 -1.6 90)
			(layer "B.Fab")
			(effects
				(font
					(size 0.7 0.7)
					(thickness 0.15)
				)
				(justify left bottom mirror)
			)
		)
		(property "Datasheet" "https://www.murata.com/products/productdetail?partno=GRM188R60J476ME15%23"
			(at 0 0 270)
			(layer "F.Fab")
			(hide yes)
			(effects
				(font
					(size 1.27 1.27)
					(thickness 0.15)
				)
			)
		)
		(property "Author" "Antmicro"
			(at -30.525499 308.279501 0)
			(layer "B.Fab")
			(hide yes)
			(effects
				(font
					(size 1 1)
					(thickness 0.15)
				)
				(justify mirror)
			)
		)
		(property "Dielectric" ""
			(at -30.525499 308.279501 0)
			(layer "B.Fab")
			(hide yes)
			(effects
				(font
					(size 1 1)
					(thickness 0.15)
				)
				(justify mirror)
			)
		)
		(property "License" "Apache-2.0"
			(at -30.525499 308.279501 0)
			(layer "B.Fab")
			(hide yes)
			(effects
				(font
					(size 1 1)
					(thickness 0.15)
				)
				(justify mirror)
			)
		)
		(property "MPN" "GRM188R60J476ME15D"
			(at -30.525499 308.279501 0)
			(layer "B.Fab")
			(hide yes)
			(effects
				(font
					(size 1 1)
					(thickness 0.15)
				)
				(justify mirror)
			)
		)
		(property "Manufacturer" "Murata"
			(at -30.525499 308.279501 0)
			(layer "B.Fab")
			(hide yes)
			(effects
				(font
					(size 1 1)
					(thickness 0.15)
				)
				(justify mirror)
			)
		)
		(property "Val" "47u"
			(at -30.525499 308.279501 0)
			(layer "B.Fab")
			(hide yes)
			(effects
				(font
					(size 1 1)
					(thickness 0.15)
				)
				(justify mirror)
			)
		)
		(property "Voltage" ""
			(at -30.525499 308.279501 0)
			(layer "B.Fab")
			(hide yes)
			(effects
				(font
					(size 1 1)
					(thickness 0.15)
				)
				(justify mirror)
			)
		)
		(sheetname "/FPGA power/")
		(sheetfile "fpga-power.kicad_sch")
		(attr smd)
		(fp_line
			(start -0.3 0.3)
			(end 0.3 0.3)
			(stroke
				(width 0.15)
				(type solid)
			)
			(layer "B.SilkS")
		)
		(fp_line
			(start -0.3 -0.3)
			(end 0.3 -0.3)
			(stroke
				(width 0.15)
				(type solid)
			)
			(layer "B.SilkS")
		)
		(fp_rect
			(start -1.24 0.7)
			(end 1.24 -0.7)
			(stroke
				(width 0.05)
				(type solid)
			)
			(fill no)
			(layer "B.CrtYd")
		)
		(fp_rect
			(start -0.8 0.4)
			(end 0.8 -0.4)
			(stroke
				(width 0.15)
				(type solid)
			)
			(fill no)
			(layer "B.Fab")
		)
		(pad "1" smd roundrect
			(at -0.7 0 270)
			(size 0.6 0.8)
			(layers "B.Cu" "B.Mask" "B.Paste")
			(roundrect_rratio 0.2)
			(net 206 "+1V1")
			(pintype "passive")
		)
		(pad "2" smd roundrect
			(at 0.7 0 270)
			(size 0.6 0.8)
			(layers "B.Cu" "B.Mask" "B.Paste")
			(roundrect_rratio 0.2)
			(net 1 "GND")
			(pintype "passive")
		)
	)
	(footprint "antmicro-footprints:C_0402_1005Metric"
		(layer "B.Cu")
		(at 143.875501 165.301)
		(descr "Capacitor SMD 0402 (1005 Metric), square (rectangular) end terminal, IPC_7351 nominal, (Body size source: IPC-SM-782 page 76, https://www.pcb-3d.com/wordpress/wp-content/uploads/ipc-sm-782a_amendment_1_and_2.pdf)")
		(tags "capacitor 0402")
		(property "Reference" "C69"
			(at 0 1.17 180)
			(layer "B.SilkS")
			(hide yes)
			(effects
				(font
					(size 0.7 0.7)
					(thickness 0.15)
				)
				(justify left bottom mirror)
			)
		)
		(property "Value" "C_100n_0402"
			(at 0 -1.169 180)
			(layer "B.Fab")
			(effects
				(font
					(size 0.7 0.7)
					(thickness 0.15)
				)
				(justify left bottom mirror)
			)
		)
		(property "Datasheet" "https://www.murata.com/products/productdetail?partno=GRM155R61H104KE14%23"
			(at 0 0 0)
			(layer "F.Fab")
			(hide yes)
			(effects
				(font
					(size 1.27 1.27)
					(thickness 0.15)
				)
			)
		)
		(property "Author" "Antmicro"
			(at 0 0 0)
			(layer "B.Fab")
			(hide yes)
			(effects
				(font
					(size 1 1)
					(thickness 0.15)
				)
				(justify mirror)
			)
		)
		(property "Dielectric" "X5R"
			(at 0 0 0)
			(layer "B.Fab")
			(hide yes)
			(effects
				(font
					(size 1 1)
					(thickness 0.15)
				)
				(justify mirror)
			)
		)
		(property "License" "Apache-2.0"
			(at 0 0 0)
			(layer "B.Fab")
			(hide yes)
			(effects
				(font
					(size 1 1)
					(thickness 0.15)
				)
				(justify mirror)
			)
		)
		(property "MPN" "GRM155R61H104KE14D"
			(at 0 0 0)
			(layer "B.Fab")
			(hide yes)
			(effects
				(font
					(size 1 1)
					(thickness 0.15)
				)
				(justify mirror)
			)
		)
		(property "Manufacturer" "Murata"
			(at 0 0 0)
			(layer "B.Fab")
			(hide yes)
			(effects
				(font
					(size 1 1)
					(thickness 0.15)
				)
				(justify mirror)
			)
		)
		(property "Val" "100n"
			(at 0 0 0)
			(layer "B.Fab")
			(hide yes)
			(effects
				(font
					(size 1 1)
					(thickness 0.15)
				)
				(justify mirror)
			)
		)
		(property "Voltage" "50V"
			(at 0 0 0)
			(layer "B.Fab")
			(hide yes)
			(effects
				(font
					(size 1 1)
					(thickness 0.15)
				)
				(justify mirror)
			)
		)
		(sheetname "/FPGA power/")
		(sheetfile "fpga-power.kicad_sch")
		(attr smd)
		(fp_rect
			(start -0.9656 0.4572)
			(end 0.9652 -0.4828)
			(stroke
				(width 0.05)
				(type solid)
			)
			(fill no)
			(layer "B.CrtYd")
		)
		(fp_line
			(start -0.5 -0.248)
			(end -0.5 0.25)
			(stroke
				(width 0.15)
				(type solid)
			)
			(layer "B.Fab")
		)
		(fp_line
			(start -0.5 0.25)
			(end 0.498 0.25)
			(stroke
				(width 0.15)
				(type solid)
			)
			(layer "B.Fab")
		)
		(fp_line
			(start 0.498 -0.248)
			(end -0.5 -0.248)
			(stroke
				(width 0.15)
				(type solid)
			)
			(layer "B.Fab")
		)
		(fp_line
			(start 0.498 0.25)
			(end 0.498 -0.248)
			(stroke
				(width 0.15)
				(type solid)
			)
			(layer "B.Fab")
		)
		(pad "1" smd roundrect
			(at -0.5 0 270)
			(size 0.6 0.6)
			(layers "B.Cu" "B.Mask" "B.Paste")
			(roundrect_rratio 0.25)
			(net 1 "GND")
			(pintype "passive")
		)
		(pad "2" smd roundrect
			(at 0.498 0)
			(size 0.6 0.6)
			(layers "B.Cu" "B.Mask" "B.Paste")
			(roundrect_rratio 0.25)
			(net 206 "+1V1")
			(pintype "passive")
		)
	)
	(footprint "antmicro-footprints:TP_SMD_1mm"
		(layer "B.Cu")
		(at 200.4 189.5 180)
		(property "Reference" "TP60"
			(at -1.43 0.68 0)
			(layer "B.SilkS")
			(effects
				(font
					(size 0.7 0.7)
					(thickness 0.15)
				)
				(justify left bottom mirror)
			)
		)
		(property "Value" "TP_1mm_SMD"
			(at 0 -1.4 0)
			(layer "B.Fab")
			(effects
				(font
					(size 0.7 0.7)
					(thickness 0.15)
				)
				(justify left bottom mirror)
			)
		)
		(property "MPN" ""
			(at 0 0 0)
			(unlocked yes)
			(layer "B.Fab")
			(hide yes)
			(effects
				(font
					(size 1 1)
					(thickness 0.15)
				)
				(justify mirror)
			)
		)
		(property "Manufacturer" ""
			(at 0 0 0)
			(unlocked yes)
			(layer "B.Fab")
			(hide yes)
			(effects
				(font
					(size 1 1)
					(thickness 0.15)
				)
				(justify mirror)
			)
		)
		(property "Author" "Antmicro"
			(at 0 0 0)
			(unlocked yes)
			(layer "B.Fab")
			(hide yes)
			(effects
				(font
					(size 1 1)
					(thickness 0.15)
				)
				(justify mirror)
			)
		)
		(property "License" "Apache-2.0"
			(at 0 0 0)
			(unlocked yes)
			(layer "B.Fab")
			(hide yes)
			(effects
				(font
					(size 1 1)
					(thickness 0.15)
				)
				(justify mirror)
			)
		)
		(sheetname "/Supply/")
		(sheetfile "supply.kicad_sch")
		(attr exclude_from_pos_files)
		(fp_circle
			(center 0 0)
			(end 0.6 0)
			(stroke
				(width 0.05)
				(type default)
			)
			(fill no)
			(layer "B.CrtYd")
		)
		(fp_text user "Author: Antmicro"
			(at -0.5 -4 0)
			(layer "B.Fab")
			(effects
				(font
					(size 0.7 0.7)
					(thickness 0.15)
				)
				(justify left bottom mirror)
			)
		)
		(fp_text user "License: Apache-2.0"
			(at -0.5 -5.2 0)
			(layer "B.Fab")
			(effects
				(font
					(size 0.7 0.7)
					(thickness 0.15)
				)
				(justify left bottom mirror)
			)
		)
		(fp_text user "${REFERENCE}"
			(at -0.5 -2.8 0)
			(layer "B.Fab")
			(effects
				(font
					(size 0.7 0.7)
					(thickness 0.15)
				)
				(justify left bottom mirror)
			)
		)
		(pad "1" smd circle
			(at 0 0 180)
			(size 1 1)
			(layers "B.Cu" "B.Mask")
			(net 58 "/Supply/1V7_local")
			(pinfunction "1")
			(pintype "passive")
		)
	)
	(footprint "antmicro-footprints:R_0402_1005Metric"
		(layer "B.Cu")
		(at 123.15 182)
		(descr "Resistor SMD 0402")
		(tags "resistor SMD 0402")
		(property "Reference" "R5"
			(at -1.122484 0.772697 180)
			(layer "B.SilkS")
			(hide yes)
			(effects
				(font
					(size 0.7 0.7)
					(thickness 0.15)
				)
				(justify left bottom mirror)
			)
		)
		(property "Value" "R_4k7_0402"
			(at -1.011843 -1.772047 180)
			(layer "B.Fab")
			(effects
				(font
					(size 0.7 0.7)
					(thickness 0.15)
				)
				(justify left bottom mirror)
			)
		)
		(property "Datasheet" "https://www.bourns.com/docs/product-datasheets/cr.pdf"
			(at 0 0 0)
			(layer "F.Fab")
			(hide yes)
			(effects
				(font
					(size 1.27 1.27)
					(thickness 0.15)
				)
			)
		)
		(property "Author" "Antmicro"
			(at 0 0 0)
			(layer "B.Fab")
			(hide yes)
			(effects
				(font
					(size 1 1)
					(thickness 0.15)
				)
				(justify mirror)
			)
		)
		(property "License" "Apache-2.0"
			(at 0 0 0)
			(layer "B.Fab")
			(hide yes)
			(effects
				(font
					(size 1 1)
					(thickness 0.15)
				)
				(justify mirror)
			)
		)
		(property "MPN" "CR0402-FX-4701GLF"
			(at 0 0 0)
			(layer "B.Fab")
			(hide yes)
			(effects
				(font
					(size 1 1)
					(thickness 0.15)
				)
				(justify mirror)
			)
		)
		(property "Manufacturer" "Bourns"
			(at 0 0 0)
			(layer "B.Fab")
			(hide yes)
			(effects
				(font
					(size 1 1)
					(thickness 0.15)
				)
				(justify mirror)
			)
		)
		(property "Tolerance" "1%"
			(at 0 0 0)
			(layer "B.Fab")
			(hide yes)
			(effects
				(font
					(size 1 1)
					(thickness 0.15)
				)
				(justify mirror)
			)
		)
		(property "Val" "4k7"
			(at 0 0 0)
			(layer "B.Fab")
			(hide yes)
			(effects
				(font
					(size 1 1)
					(thickness 0.15)
				)
				(justify mirror)
			)
		)
		(sheetname "/HyperRAM + QSPI Flash/")
		(sheetfile "hyperram-flash.kicad_sch")
		(attr smd)
		(fp_rect
			(start -0.93 0.47)
			(end 0.93 -0.47)
			(stroke
				(width 0.05)
				(type solid)
			)
			(fill no)
			(layer "B.CrtYd")
		)
		(fp_rect
			(start -0.5 0.25)
			(end 0.5 -0.25)
			(stroke
				(width 0.15)
				(type solid)
			)
			(fill no)
			(layer "B.Fab")
		)
		(pad "1" smd roundrect
			(at -0.485 0)
			(size 0.59 0.64)
			(layers "B.Cu" "B.Mask" "B.Paste")
			(roundrect_rratio 0.25)
			(net 200 "+3V3")
			(pintype "passive")
		)
		(pad "2" smd roundrect
			(at 0.485 0)
			(size 0.59 0.64)
			(layers "B.Cu" "B.Mask" "B.Paste")
			(roundrect_rratio 0.25)
			(net 361 "/HyperRAM + QSPI Flash/IO2")
			(pintype "passive")
		)
	)
)
